FILE_TYPE = CONNECTIVITY;
{Allegro Design Entry HDL 17.2-2016 S081 (4005846) 1/11/2022}
"PAGE_NUMBER" = 136;
0"NC";
1"P3V3_AUX\g";
2"P3V3_AUX\g";
3"P3V3_AUX\g";
4"P3V3_AUX\g";
5"P3V3_AUX\g";
6"P3V3_AUX\g";
7"P3V3_AUX\g";
8"GND\g";
9"GND\g";
10"GND\g";
11"GND\g";
12"GND\g";
13"GND\g";
14"GND\g";
15"GND\g";
16"GND\g";
17"GND\g";
18"GND\g";
19"GND\g";
20"GND\g";
21"GND\g";
22"GND\g";
23"GND\g";
24"GND\g";
25"GND\g";
26"GND\g";
27"GND\g";
28"GND\g";
29"FM_P2E_SWB";
30"P2E_MB_BMC_RX_R1_DN<0>";
31"P2E_MB_BMC_RX_R1_DP<0>";
32"P2E_MB_BMC_TX_C_R1_DN<0>";
33"P2E_MB_BMC_TX_C_R1_DP<0>";
34"FM_P2E_EQB1";
35"FM_P2E_EQB0";
36"FM_P2E_SWA";
37"FM_P2E_FGA";
38"FM_P2E_EQB1";
39"FM_P2E_EQB0";
40"FM_P2E_MODE";
41"CLK_GEN2_GPU_FPGA_OE_OR_N";
42"FM_P2E_SWB";
43"FM_P2E_SWA";
44"FM_P2E_EQA1";
45"FM_P2E_EQA0";
46"FM_P2E_FGB";
47"FM_P2E_FGA";
48"PU_TEST";
49"FM_P2E_EN_N";
50"FM_P2E_FGB";
51"FM_P2E_EQA0";
52"FM_P2E_EQA1";
53"FM_P2E_MODE";
54"CLK_GEN2_GPU_FPGA_OE_OR_N";
55"P2E_MB_BMC_TX_BUF_DP<0>";
56"P2E_MB_BMC_TX_BUF_DN<0>";
57"P2E_MB_BMC_RX_BUF_C_DP<0>";
58"P2E_MB_BMC_RX_BUF_C_DN<0>";
%"UNIVERSAL_GND"
"1","(-4325,-2875)","0","logical_power","I1";
;
ROOM"IO_SLOT"
CDS_LIB"logical_power"
HDL_POWER"GND";
"A"8;
%"UNIVERSAL_POWER"
"1","(-3950,-1700)","0","logical_power","I10";
;
HDL_POWER"P3V3_AUX"
CDS_LIB"logical_power";
"A"4;
%"UNIVERSAL_GND"
"1","(-4500,-1150)","0","logical_power","I11";
;
ROOM"IO_SLOT"
CDS_LIB"logical_power"
HDL_POWER"GND";
"A"12;
%"Q_RES"
"2","(-4500,-800)","0","pure_quanta","I12";
;
PART_NUMBER"CS36802FB04"
MATERIAL"EMPTY"
PACK_TYPE"0402LF"
VALUE"68K"
TOLERANCE"1%"
WATTAGE"1/16W"
$LOCATION"R3267"
CDS_LIB"pure_quanta"
CDS_LOCATION"R3267"
$SEC"1"
CDS_SEC"1";
"A"
$PN"1"50;
"B"
$PN"2"12;
%"UNIVERSAL_GND"
"1","(-4125,-1150)","0","logical_power","I13";
;
ROOM"IO_SLOT"
CDS_LIB"logical_power"
HDL_POWER"GND";
"A"13;
%"Q_RES"
"2","(-4125,-800)","0","pure_quanta","I14";
;
PART_NUMBER"CS21002FB06"
VALUE"1K"
TOLERANCE"1%"
PACK_TYPE"0402LF"
MATERIAL"EMPTY"
WATTAGE"1/16W"
$LOCATION"R3270"
CDS_LIB"pure_quanta"
CDS_LOCATION"R3270"
$SEC"1"
CDS_SEC"1";
"A"
$PN"1"50;
"B"
$PN"2"13;
%"Q_RES"
"2","(-4125,-275)","0","pure_quanta","I15";
;
PART_NUMBER"CS21002FB06"
PACK_TYPE"0402LF"
MATERIAL"EMPTY"
TOLERANCE"1%"
VALUE"1K"
WATTAGE"1/16W"
$LOCATION"R3269"
CDS_LIB"pure_quanta"
CDS_LOCATION"R3269"
$SEC"1"
CDS_SEC"1";
"A"
$PN"1"5;
"B"
$PN"2"50;
%"Q_RES"
"2","(-3075,-2000)","0","pure_quanta","I16";
;
PART_NUMBER"CS21002FB06"
WATTAGE"1/16W"
VALUE"1K"
TOLERANCE"1%"
MATERIAL"EMPTY"
PACK_TYPE"0402LF"
$LOCATION"R3277"
CDS_LIB"pure_quanta"
CDS_LOCATION"R3277"
$SEC"1"
CDS_SEC"1";
"A"
$PN"1"4;
"B"
$PN"2"51;
%"UNIVERSAL_GND"
"1","(-3650,-1150)","0","logical_power","I17";
;
ROOM"IO_SLOT"
CDS_LIB"logical_power"
HDL_POWER"GND";
"A"14;
%"Q_RES"
"2","(-3650,-825)","0","pure_quanta","I18";
;
PART_NUMBER"CS36802FB04"
TOLERANCE"1%"
WATTAGE"1/16W"
MATERIAL"EMPTY"
PACK_TYPE"0402LF"
VALUE"68K"
$LOCATION"R3273"
CDS_LIB"pure_quanta"
CDS_LOCATION"R3273"
$SEC"1"
CDS_SEC"1";
"A"
$PN"1"37;
"B"
$PN"2"14;
%"UNIVERSAL_GND"
"1","(-3250,-1150)","0","logical_power","I19";
;
ROOM"IO_SLOT"
CDS_LIB"logical_power"
HDL_POWER"GND";
"A"15;
%"Q_RES"
"2","(-4325,-2525)","0","pure_quanta","I2";
;
PART_NUMBER"CS36802FB04"
VALUE"68K"
PACK_TYPE"0402LF"
TOLERANCE"1%"
WATTAGE"1/16W"
MATERIAL"EMPTY"
$LOCATION"R3268"
CDS_LIB"pure_quanta"
CDS_LOCATION"R3268"
$SEC"1"
CDS_SEC"1";
"A"
$PN"1"52;
"B"
$PN"2"8;
%"Q_RES"
"2","(-3250,-850)","0","pure_quanta","I20";
;
PART_NUMBER"CS21002FB06"
PACK_TYPE"0402LF"
VALUE"1K"
TOLERANCE"1%"
WATTAGE"1/16W"
MATERIAL"EMPTY"
$LOCATION"R3276"
CDS_LIB"pure_quanta"
CDS_LOCATION"R3276"
$SEC"1"
CDS_SEC"1";
"A"
$PN"1"37;
"B"
$PN"2"15;
%"Q_RES"
"2","(-3250,-275)","0","pure_quanta","I21";
;
PART_NUMBER"CS21002FB06"
WATTAGE"1/16W"
PACK_TYPE"0402LF"
MATERIAL"EMPTY"
VALUE"1K"
TOLERANCE"1%"
$LOCATION"R3275"
CDS_LIB"pure_quanta"
CDS_LOCATION"R3275"
$SEC"1"
CDS_SEC"1";
"A"
$PN"1"5;
"B"
$PN"2"37;
%"UNIVERSAL_GND"
"1","(-2075,-2900)","0","logical_power","I22";
;
ROOM"IO_SLOT"
CDS_LIB"logical_power"
HDL_POWER"GND";
"A"16;
%"Q_RES"
"2","(-2075,-2550)","0","pure_quanta","I23";
;
PART_NUMBER"CS36802FB04"
MATERIAL"EMPTY"
PACK_TYPE"0402LF"
VALUE"68K"
WATTAGE"1/16W"
TOLERANCE"1%"
$LOCATION"R3279"
CDS_LIB"pure_quanta"
CDS_LOCATION"R3279"
$SEC"1"
CDS_SEC"1";
"A"
$PN"1"38;
"B"
$PN"2"16;
%"UNIVERSAL_GND"
"1","(-1700,-2900)","0","logical_power","I24";
;
ROOM"IO_SLOT"
CDS_LIB"logical_power"
HDL_POWER"GND";
"A"17;
%"Q_RES"
"2","(-1700,-2550)","0","pure_quanta","I25";
;
PART_NUMBER"CS21002FB06"
MATERIAL"EMPTY"
WATTAGE"1/16W"
PACK_TYPE"0402LF"
TOLERANCE"1%"
VALUE"1K"
$LOCATION"R3281"
CDS_LIB"pure_quanta"
CDS_LOCATION"R3281"
$SEC"1"
CDS_SEC"1";
"A"
$PN"1"38;
"B"
$PN"2"17;
%"UNIVERSAL_GND"
"1","(-1225,-2900)","0","logical_power","I26";
;
ROOM"IO_SLOT"
CDS_LIB"logical_power"
HDL_POWER"GND";
"A"18;
%"Q_RES"
"2","(-1225,-2575)","0","pure_quanta","I27";
;
PART_NUMBER"CS36802FB04"
MATERIAL"EMPTY"
PACK_TYPE"0402LF"
VALUE"68K"
WATTAGE"1/16W"
TOLERANCE"1%"
$LOCATION"R3282"
CDS_LIB"pure_quanta"
CDS_LOCATION"R3282"
$SEC"1"
CDS_SEC"1";
"A"
$PN"1"39;
"B"
$PN"2"18;
%"UNIVERSAL_GND"
"1","(-3950,-2875)","0","logical_power","I3";
;
ROOM"IO_SLOT"
CDS_LIB"logical_power"
HDL_POWER"GND";
"A"9;
%"Q_RES"
"2","(-1700,-2025)","0","pure_quanta","I32";
;
PART_NUMBER"CS21002FB06"
VALUE"1K"
MATERIAL"EMPTY"
TOLERANCE"1%"
WATTAGE"1/16W"
PACK_TYPE"0402LF"
$LOCATION"R3280"
CDS_LIB"pure_quanta"
CDS_LOCATION"R3280"
$SEC"1"
CDS_SEC"1";
"A"
$PN"1"1;
"B"
$PN"2"38;
%"UNIVERSAL_POWER"
"1","(-1700,-1725)","0","logical_power","I33";
;
HDL_POWER"P3V3_AUX"
CDS_LIB"logical_power";
"A"1;
%"UNIVERSAL_POWER"
"1","(-4125,25)","0","logical_power","I34";
;
HDL_POWER"P3V3_AUX"
CDS_LIB"logical_power";
"A"5;
%"Q_RES"
"2","(-3950,-2525)","0","pure_quanta","I4";
;
PART_NUMBER"CS21002FB06"
MATERIAL"EMPTY"
WATTAGE"1/16W"
VALUE"1K"
TOLERANCE"1%"
PACK_TYPE"0402LF"
$LOCATION"R3272"
CDS_LIB"pure_quanta"
CDS_LOCATION"R3272"
$SEC"1"
CDS_SEC"1";
"A"
$PN"1"52;
"B"
$PN"2"9;
%"UNIVERSAL_GND"
"1","(-3275,2000)","0","logical_power","I47";
;
CDS_LIB"logical_power"
HDL_POWER"GND";
"A"19;
%"Q_CAP"
"1","(-3275,2350)","0","pure_quanta","I48";
;
PART_NUMBER"CH6104KEA00"
PACK_TYPE"C0805"
MATERIAL"X6S"
TOLERANCE"10%"
VOLTAGE"25V"
VALUE"10UF"
ROOM"PCIE REDRIVER1_BOM1"
$LOCATION"C1867"
CDS_LIB"pure_quanta"
CDS_LOCATION"C1867"
$SEC"1"
CDS_SEC"1";
"B"
$PN"2"19;
"A"
$PN"1"3;
%"Q_CAP"
"1","(-2900,2350)","0","pure_quanta","I49";
;
PART_NUMBER"CH4104K1B00"
VOLTAGE"25V"
TOLERANCE"10%"
MATERIAL"X7R"
PACK_TYPE"0402"
VALUE"0.1UF"
ROOM"PCIE REDRIVER1_BOM1"
$LOCATION"C1863"
CDS_LIB"pure_quanta"
CDS_LOCATION"C1863"
$SEC"1"
CDS_SEC"1";
"B"
$PN"2"19;
"A"
$PN"1"3;
%"UNIVERSAL_GND"
"1","(-3475,-2875)","0","logical_power","I5";
;
ROOM"IO_SLOT"
CDS_LIB"logical_power"
HDL_POWER"GND";
"A"10;
%"PI3EQX12902AZLEX"
"1","(-1300,1525)","0","pure_quanta","I50";
;
PART_NUMBER"AL012902001"
VALUE"PI3EQX12902AZLEX"
PART_TYPE"SMLF"
MATERIAL"IC"
ROOM"PCIE REDRIVER1_BOM1"
$LOCATION"U237"
NEEDS_NO_SIZE"TRUE"
CDS_LMAN_SYM_OUTLINE"-300,775,300,-775"
CDS_LIB"pure_quanta"
CDS_LOCATION"U237"
$SEC"1"
CDS_SEC"1";
"GND_TH"
$PN"TH"25;
"MODE"
$PN"30"53;
"SWA"
$PN"29"43;
"GND7"
$PN"28"25;
"FGA"
$PN"27"47;
"EQA1"
$PN"26"44;
"VDD4"
$PN"25"3;
"AOP"
$PN"24"55;
"AON"
$PN"23"56;
"GND6"
$PN"22"25;
"EQA0"
$PN"21"45;
"EQB0"
$PN"20"35;
"GND5"
$PN"19"25;
"BIN"
$PN"18"30;
"BIP"
$PN"17"31;
"VDD3"
$PN"16"3;
"EQB1"
$PN"15"34;
"FGB"
$PN"14"46;
"GND4"
$PN"13"25;
"SWB"
$PN"12"42;
"EN# \B"
$PN"11"49;
"VDD2"
$PN"10"3;
"BOP"
$PN"9"57;
"BON"
$PN"8"58;
"GND3"
$PN"7"25;
"GND2"
$PN"6"25;
"TEST# \B"
$PN"5"48;
"GND1"
$PN"4"25;
"AIN"
$PN"3"32;
"AIP"
$PN"2"33;
"VDD1"
$PN"1"3;
%"Q_CAP"
"1","(-2625,2350)","0","pure_quanta","I51";
;
PART_NUMBER"CH4104K1B00"
MATERIAL"X7R"
VALUE"0.1UF"
VOLTAGE"25V"
TOLERANCE"10%"
PACK_TYPE"0402"
ROOM"PCIE REDRIVER1_BOM1"
$LOCATION"C1864"
CDS_LIB"pure_quanta"
CDS_LOCATION"C1864"
$SEC"1"
CDS_SEC"1";
"B"
$PN"2"19;
"A"
$PN"1"3;
%"Q_CAP"
"1","(-2350,2350)","0","pure_quanta","I52";
;
PART_NUMBER"CH4104K1B00"
PACK_TYPE"0402"
MATERIAL"X7R"
VOLTAGE"25V"
TOLERANCE"10%"
VALUE"0.1UF"
ROOM"PCIE REDRIVER1_BOM1"
$LOCATION"C1865"
CDS_LIB"pure_quanta"
CDS_LOCATION"C1865"
$SEC"1"
CDS_SEC"1";
"B"
$PN"2"19;
"A"
$PN"1"3;
%"Q_CAP"
"1","(-2125,2350)","0","pure_quanta","I53";
;
PART_NUMBER"CH4104K1B00"
PACK_TYPE"0402"
MATERIAL"X7R"
VALUE"0.1UF"
VOLTAGE"25V"
TOLERANCE"10%"
ROOM"PCIE REDRIVER1_BOM1"
$LOCATION"C1866"
CDS_LIB"pure_quanta"
CDS_LOCATION"C1866"
$SEC"1"
CDS_SEC"1";
"B"
$PN"2"19;
"A"
$PN"1"3;
%"UNIVERSAL_POWER"
"1","(-1875,2750)","0","logical_power","I54";
;
HDL_POWER"P3V3_AUX"
CDS_LIB"logical_power";
"A"3;
%"UNIVERSAL_GND"
"1","(-825,-2900)","0","logical_power","I55";
;
ROOM"IO_SLOT"
CDS_LIB"logical_power"
HDL_POWER"GND";
"A"20;
%"Q_RES"
"2","(-825,-2600)","0","pure_quanta","I56";
;
PART_NUMBER"CS21002FB06"
PACK_TYPE"0402LF"
VALUE"1K"
TOLERANCE"1%"
WATTAGE"1/16W"
MATERIAL"CHIP"
ROOM"PCIE REDRIVER1_BOM1"
$LOCATION"R3284"
CDS_LIB"pure_quanta"
CDS_LOCATION"R3284"
$SEC"1"
CDS_SEC"1";
"A"
$PN"1"39;
"B"
$PN"2"20;
%"Q_RES"
"2","(-825,-2025)","0","pure_quanta","I57";
;
PART_NUMBER"CS21002FB06"
WATTAGE"1/16W"
MATERIAL"EMPTY"
TOLERANCE"1%"
VALUE"1K"
PACK_TYPE"0402LF"
$LOCATION"R3283"
CDS_LIB"pure_quanta"
CDS_LOCATION"R3283"
$SEC"1"
CDS_SEC"1";
"A"
$PN"1"1;
"B"
$PN"2"39;
%"Q_RES"
"2","(-3475,-2550)","0","pure_quanta","I6";
;
PART_NUMBER"CS36802FB04"
MATERIAL"EMPTY"
PACK_TYPE"0402LF"
VALUE"68K"
WATTAGE"1/16W"
TOLERANCE"1%"
$LOCATION"R3274"
CDS_LIB"pure_quanta"
CDS_LOCATION"R3274"
$SEC"1"
CDS_SEC"1";
"A"
$PN"1"51;
"B"
$PN"2"10;
%"UNIVERSAL_GND"
"1","(-50,-1150)","0","logical_power","I60";
;
ROOM"IO_SLOT"
CDS_LIB"logical_power"
HDL_POWER"GND";
"A"21;
%"Q_RES"
"2","(-50,-800)","0","pure_quanta","I61";
;
PART_NUMBER"CS36802FB04"
TOLERANCE"1%"
WATTAGE"1/16W"
MATERIAL"EMPTY"
VALUE"68K"
PACK_TYPE"0402LF"
$LOCATION"R3285"
CDS_LIB"pure_quanta"
CDS_LOCATION"R3285"
$SEC"1"
CDS_SEC"1";
"A"
$PN"1"29;
"B"
$PN"2"21;
%"UNIVERSAL_GND"
"1","(325,-1150)","0","logical_power","I62";
;
ROOM"IO_SLOT"
CDS_LIB"logical_power"
HDL_POWER"GND";
"A"22;
%"Q_RES"
"2","(325,-800)","0","pure_quanta","I63";
;
PART_NUMBER"CS21002FB06"
VALUE"1K"
TOLERANCE"1%"
WATTAGE"1/16W"
MATERIAL"EMPTY"
PACK_TYPE"0402LF"
$LOCATION"R3287"
CDS_LIB"pure_quanta"
CDS_LOCATION"R3287"
$SEC"1"
CDS_SEC"1";
"A"
$PN"1"29;
"B"
$PN"2"22;
%"Q_RES"
"2","(325,-275)","0","pure_quanta","I64";
;
PART_NUMBER"CS21002FB06"
VALUE"1K"
PACK_TYPE"0402LF"
TOLERANCE"1%"
WATTAGE"1/16W"
MATERIAL"EMPTY"
$LOCATION"R3286"
CDS_LIB"pure_quanta"
CDS_LOCATION"R3286"
$SEC"1"
CDS_SEC"1";
"A"
$PN"1"6;
"B"
$PN"2"29;
%"UNIVERSAL_GND"
"1","(800,-1150)","0","logical_power","I65";
;
ROOM"IO_SLOT"
CDS_LIB"logical_power"
HDL_POWER"GND";
"A"23;
%"Q_RES"
"2","(800,-825)","0","pure_quanta","I66";
;
PART_NUMBER"CS36802FB04"
WATTAGE"1/16W"
TOLERANCE"1%"
PACK_TYPE"0402LF"
MATERIAL"EMPTY"
VALUE"68K"
$LOCATION"R3288"
CDS_LIB"pure_quanta"
CDS_LOCATION"R3288"
$SEC"1"
CDS_SEC"1";
"A"
$PN"1"36;
"B"
$PN"2"23;
%"UNIVERSAL_GND"
"1","(1200,-1150)","0","logical_power","I67";
;
ROOM"IO_SLOT"
CDS_LIB"logical_power"
HDL_POWER"GND";
"A"24;
%"Q_RES"
"2","(1200,-850)","0","pure_quanta","I68";
;
PART_NUMBER"CS21002FB06"
PACK_TYPE"0402LF"
MATERIAL"EMPTY"
WATTAGE"1/16W"
TOLERANCE"1%"
VALUE"1K"
$LOCATION"R3290"
CDS_LIB"pure_quanta"
CDS_LOCATION"R3290"
$SEC"1"
CDS_SEC"1";
"A"
$PN"1"36;
"B"
$PN"2"24;
%"Q_RES"
"2","(1200,-275)","0","pure_quanta","I69";
;
PART_NUMBER"CS21002FB06"
WATTAGE"1/16W"
VALUE"1K"
TOLERANCE"1%"
MATERIAL"EMPTY"
PACK_TYPE"0402LF"
$LOCATION"R3289"
CDS_LIB"pure_quanta"
CDS_LOCATION"R3289"
$SEC"1"
CDS_SEC"1";
"A"
$PN"1"6;
"B"
$PN"2"36;
%"UNIVERSAL_GND"
"1","(-3075,-2875)","0","logical_power","I7";
;
ROOM"IO_SLOT"
CDS_LIB"logical_power"
HDL_POWER"GND";
"A"11;
%"UNIVERSAL_GND"
"1","(-775,625)","0","logical_power","I72";
;
CDS_LIB"logical_power"
HDL_POWER"GND";
"A"25;
%"Q_RES"
"1","(-250,1500)","0","pure_quanta","I73";
;
PART_NUMBER"CS00002JB13"
VALUE"0"
PACK_TYPE"0402LF"
MATERIAL"CHIP"
ROOM"PCIE REDRIVER1_BOM1"
$LOCATION"R4537"
WATTAGE"1/16W"
TOLERANCE"5%"
CDS_LIB"pure_quanta"
CDS_LOCATION"R4537"
$SEC"1"
CDS_SEC"1";
"B"
$PN"2"41;
"A"
$PN"1"49;
%"UNIVERSAL_POWER"
"1","(325,25)","0","logical_power","I74";
;
HDL_POWER"P3V3_AUX"
CDS_LIB"logical_power";
"A"6;
%"Q_RES"
"2","(-3075,-2575)","0","pure_quanta","I8";
;
PART_NUMBER"CS21002FB06"
MATERIAL"CHIP"
WATTAGE"1/16W"
PACK_TYPE"0402LF"
TOLERANCE"1%"
VALUE"1K"
ROOM"PCIE REDRIVER1_BOM1"
$LOCATION"R3278"
CDS_LIB"pure_quanta"
CDS_LOCATION"R3278"
$SEC"1"
CDS_SEC"1";
"A"
$PN"1"51;
"B"
$PN"2"11;
%"UNIVERSAL_GND"
"1","(1850,1150)","0","logical_power","I81";
;
ROOM"IO_SLOT"
CDS_LIB"logical_power"
HDL_POWER"GND";
"A"26;
%"Q_RES"
"2","(1850,1375)","0","pure_quanta","I82";
;
PART_NUMBER"CS24702FB06"
TOLERANCE"1%"
PACK_TYPE"0402LF"
WATTAGE"1/16W"
MATERIAL"EMPTY"
VALUE"4.7K"
$LOCATION"R3291"
CDS_LIB"pure_quanta"
CDS_LOCATION"R3291"
$SEC"1"
CDS_SEC"1";
"A"
$PN"1"48;
"B"
$PN"2"26;
%"UNIVERSAL_GND"
"1","(3100,150)","0","logical_power","I83";
;
CDS_LIB"logical_power"
ROOM"IO_SLOT"
HDL_POWER"GND";
"A"27;
%"Q_RES"
"2","(3100,375)","0","pure_quanta","I84";
;
PART_NUMBER"CS24702FB06"
PACK_TYPE"0402LF"
TOLERANCE"1%"
VALUE"4.7K"
WATTAGE"1/16W"
MATERIAL"EMPTY"
$LOCATION"R3265"
CDS_LIB"pure_quanta"
CDS_LOCATION"R3265"
$SEC"1"
CDS_SEC"1";
"A"
$PN"1"54;
"B"
$PN"2"27;
%"Q_RES"
"2","(3100,900)","0","pure_quanta","I85";
;
PART_NUMBER"CS24702FB06"
TOLERANCE"1%"
PACK_TYPE"0402LF"
WATTAGE"1/16W"
MATERIAL"CHIP"
VALUE"4.7K"
ROOM"PCIE REDRIVER1_BOM1"
$LOCATION"R3292"
CDS_LIB"pure_quanta"
CDS_LOCATION"R3292"
$SEC"1"
CDS_SEC"1";
"A"
$PN"1"2;
"B"
$PN"2"54;
%"UNIVERSAL_POWER"
"1","(3100,1200)","0","logical_power","I86";
;
HDL_POWER"P3V3_AUX"
CDS_LIB"logical_power";
"A"2;
%"UNIVERSAL_GND"
"1","(3100,1625)","0","logical_power","I87";
;
ROOM"IO_SLOT"
CDS_LIB"logical_power"
HDL_POWER"GND";
"A"28;
%"Q_RES"
"2","(3100,1850)","0","pure_quanta","I88";
;
PART_NUMBER"CS24702FB06"
TOLERANCE"1%"
VALUE"4.7K"
WATTAGE"1/16W"
MATERIAL"EMPTY"
PACK_TYPE"0402LF"
$LOCATION"R3293"
CDS_LIB"pure_quanta"
CDS_LOCATION"R3293"
$SEC"1"
CDS_SEC"1";
"A"
$PN"1"40;
"B"
$PN"2"28;
%"Q_RES"
"2","(3100,2375)","0","pure_quanta","I89";
;
PART_NUMBER"CS24702FB06"
TOLERANCE"1%"
VALUE"4.7K"
WATTAGE"1/16W"
MATERIAL"CHIP"
PACK_TYPE"0402LF"
ROOM"PCIE REDRIVER1_BOM1"
$LOCATION"R3266"
CDS_LIB"pure_quanta"
CDS_LOCATION"R3266"
$SEC"1"
CDS_SEC"1";
"A"
$PN"1"7;
"B"
$PN"2"40;
%"Q_RES"
"2","(-3950,-2000)","0","pure_quanta","I9";
;
PART_NUMBER"CS21002FB06"
MATERIAL"EMPTY"
WATTAGE"1/16W"
VALUE"1K"
TOLERANCE"1%"
PACK_TYPE"0402LF"
$LOCATION"R3271"
CDS_LIB"pure_quanta"
CDS_LOCATION"R3271"
$SEC"1"
CDS_SEC"1";
"A"
$PN"1"4;
"B"
$PN"2"52;
%"UNIVERSAL_POWER"
"1","(3100,2675)","0","logical_power","I90";
;
HDL_POWER"P3V3_AUX"
CDS_LIB"logical_power";
"A"7;
END.
